# Jetson Orin Baseboard OCuLink Expansion — KiCad project settings (.kicad_pro: net classes, design rules, text variables)
{
  "board": {
    "3dviewports": [],
    "design_settings": {
      "defaults": {
        "apply_defaults_to_fp_fields": false,
        "apply_defaults_to_fp_shapes": false,
        "apply_defaults_to_fp_text": false,
        "board_outline_line_width": 0.05,
        "copper_line_width": 0.2,
        "copper_text_italic": false,
        "copper_text_size_h": 1.5,
        "copper_text_size_v": 1.5,
        "copper_text_thickness": 0.3,
        "copper_text_upright": false,
        "courtyard_line_width": 0.05,
        "dimension_precision": 4,
        "dimension_units": 3,
        "dimensions": {
          "arrow_length": 1270000,
          "extension_offset": 500000,
          "keep_text_aligned": true,
          "suppress_zeroes": false,
          "text_position": 0,
          "units_format": 1
        },
        "fab_line_width": 0.1,
        "fab_text_italic": false,
        "fab_text_size_h": 1.0,
        "fab_text_size_v": 1.0,
        "fab_text_thickness": 0.15,
        "fab_text_upright": false,
        "other_line_width": 0.1,
        "other_text_italic": false,
        "other_text_size_h": 1.0,
        "other_text_size_v": 1.0,
        "other_text_thickness": 0.15,
        "other_text_upright": false,
        "pads": {
          "drill": 0.0,
          "height": 0.31,
          "width": 0.91
        },
        "silk_line_width": 0.1,
        "silk_text_italic": false,
        "silk_text_size_h": 1.0,
        "silk_text_size_v": 1.0,
        "silk_text_thickness": 0.1,
        "silk_text_upright": false,
        "zones": {
          "min_clearance": 0.15
        }
      },
      "diff_pair_dimensions": [
        {
          "gap": 0.0,
          "via_gap": 0.0,
          "width": 0.0
        }
      ],
      "drc_exclusions": [],
      "meta": {
        "version": 2
      },
      "rule_severities": {
        "annular_width": "error",
        "clearance": "error",
        "connection_width": "warning",
        "copper_edge_clearance": "error",
        "copper_sliver": "warning",
        "courtyards_overlap": "error",
        "diff_pair_gap_out_of_range": "error",
        "diff_pair_uncoupled_length_too_long": "error",
        "drill_out_of_range": "error",
        "duplicate_footprints": "warning",
        "extra_footprint": "warning",
        "footprint": "error",
        "footprint_symbol_mismatch": "warning",
        "footprint_type_mismatch": "ignore",
        "hole_clearance": "error",
        "hole_near_hole": "error",
        "holes_co_located": "error",
        "invalid_outline": "error",
        "isolated_copper": "warning",
        "item_on_disabled_layer": "error",
        "items_not_allowed": "error",
        "length_out_of_range": "error",
        "lib_footprint_issues": "warning",
        "lib_footprint_mismatch": "warning",
        "malformed_courtyard": "error",
        "microvia_drill_out_of_range": "error",
        "missing_courtyard": "warning",
        "missing_footprint": "warning",
        "net_conflict": "warning",
        "npth_inside_courtyard": "warning",
        "padstack": "error",
        "pth_inside_courtyard": "warning",
        "shorting_items": "error",
        "silk_edge_clearance": "warning",
        "silk_over_copper": "warning",
        "silk_overlap": "warning",
        "skew_out_of_range": "error",
        "solder_mask_bridge": "error",
        "starved_thermal": "error",
        "text_height": "warning",
        "text_thickness": "warning",
        "through_hole_pad_without_hole": "error",
        "too_many_vias": "error",
        "track_dangling": "warning",
        "track_width": "error",
        "tracks_crossing": "error",
        "unconnected_items": "error",
        "unresolved_variable": "error",
        "via_dangling": "warning",
        "zones_intersect": "error"
      },
      "rules": {
        "max_error": 0.005,
        "min_clearance": 0.125,
        "min_connection": 0.0,
        "min_copper_edge_clearance": 0.5,
        "min_hole_clearance": 0.125,
        "min_hole_to_hole": 0.25,
        "min_microvia_diameter": 0.2,
        "min_microvia_drill": 0.1,
        "min_resolved_spokes": 1,
        "min_silk_clearance": 0.0,
        "min_text_height": 0.65,
        "min_text_thickness": 0.08,
        "min_through_hole_diameter": 0.1,
        "min_track_width": 0.125,
        "min_via_annular_width": 0.125,
        "min_via_diameter": 0.45,
        "solder_mask_to_copper_clearance": 0.0,
        "use_height_for_length_calcs": true
      },
      "teardrop_options": [
        {
          "td_onpadsmd": true,
          "td_onroundshapesonly": false,
          "td_ontrackend": false,
          "td_onviapad": true
        }
      ],
      "teardrop_parameters": [
        {
          "td_allow_use_two_tracks": true,
          "td_curve_segcount": 0,
          "td_height_ratio": 1.0,
          "td_length_ratio": 0.5,
          "td_maxheight": 2.0,
          "td_maxlen": 1.0,
          "td_on_pad_in_zone": false,
          "td_target_name": "td_round_shape",
          "td_width_to_size_filter_ratio": 0.9
        },
        {
          "td_allow_use_two_tracks": true,
          "td_curve_segcount": 0,
          "td_height_ratio": 1.0,
          "td_length_ratio": 0.5,
          "td_maxheight": 2.0,
          "td_maxlen": 1.0,
          "td_on_pad_in_zone": false,
          "td_target_name": "td_rect_shape",
          "td_width_to_size_filter_ratio": 0.9
        },
        {
          "td_allow_use_two_tracks": true,
          "td_curve_segcount": 0,
          "td_height_ratio": 1.0,
          "td_length_ratio": 0.5,
          "td_maxheight": 2.0,
          "td_maxlen": 1.0,
          "td_on_pad_in_zone": false,
          "td_target_name": "td_track_end",
          "td_width_to_size_filter_ratio": 0.9
        }
      ],
      "track_widths": [
        0.0,
        0.125,
        0.2,
        0.25,
        0.4
      ],
      "tuning_pattern_settings": {
        "diff_pair_defaults": {
          "corner_radius_percentage": 80,
          "corner_style": 1,
          "max_amplitude": 1.0,
          "min_amplitude": 0.2,
          "single_sided": false,
          "spacing": 1.0
        },
        "diff_pair_skew_defaults": {
          "corner_radius_percentage": 80,
          "corner_style": 1,
          "max_amplitude": 0.5,
          "min_amplitude": 0.2,
          "single_sided": false,
          "spacing": 0.5
        },
        "single_track_defaults": {
          "corner_radius_percentage": 80,
          "corner_style": 1,
          "max_amplitude": 1.0,
          "min_amplitude": 0.2,
          "single_sided": false,
          "spacing": 0.6
        }
      },
      "via_dimensions": [
        {
          "diameter": 0.0,
          "drill": 0.0
        },
        {
          "diameter": 0.45,
          "drill": 0.1
        }
      ],
      "zones_allow_external_fillets": false
    },
    "ipc2581": {
      "dist": "",
      "distpn": "",
      "internal_id": "",
      "mfg": "",
      "mpn": ""
    },
    "layer_presets": [],
    "viewports": []
  },
  "boards": [],
  "cvpcb": {
    "equivalence_files": []
  },
  "erc": {
    "erc_exclusions": [],
    "meta": {
      "version": 0
    },
    "pin_map": [
      [
        0,
        0,
        0,
        0,
        0,
        0,
        1,
        0,
        0,
        0,
        0,
        2
      ],
      [
        0,
        2,
        0,
        1,
        0,
        0,
        1,
        0,
        2,
        2,
        2,
        2
      ],
      [
        0,
        0,
        0,
        0,
        0,
        0,
        1,
        0,
        1,
        0,
        1,
        2
      ],
      [
        0,
        1,
        0,
        0,
        0,
        0,
        1,
        1,
        2,
        1,
        1,
        2
      ],
      [
        0,
        0,
        0,
        0,
        0,
        0,
        1,
        0,
        0,
        0,
        0,
        2
      ],
      [
        0,
        0,
        0,
        0,
        0,
        0,
        0,
        0,
        0,
        0,
        0,
        2
      ],
      [
        1,
        1,
        1,
        1,
        1,
        0,
        1,
        1,
        1,
        1,
        1,
        2
      ],
      [
        0,
        0,
        0,
        1,
        0,
        0,
        1,
        0,
        0,
        0,
        0,
        2
      ],
      [
        0,
        2,
        1,
        2,
        0,
        0,
        1,
        0,
        2,
        2,
        2,
        2
      ],
      [
        0,
        2,
        0,
        1,
        0,
        0,
        1,
        0,
        2,
        0,
        0,
        2
      ],
      [
        0,
        2,
        1,
        1,
        0,
        0,
        1,
        0,
        2,
        0,
        0,
        2
      ],
      [
        2,
        2,
        2,
        2,
        2,
        2,
        2,
        2,
        2,
        2,
        2,
        2
      ]
    ],
    "rule_severities": {
      "bus_definition_conflict": "error",
      "bus_entry_needed": "error",
      "bus_to_bus_conflict": "error",
      "bus_to_net_conflict": "error",
      "conflicting_netclasses": "error",
      "different_unit_footprint": "error",
      "different_unit_net": "error",
      "duplicate_reference": "error",
      "duplicate_sheet_names": "error",
      "endpoint_off_grid": "warning",
      "extra_units": "error",
      "global_label_dangling": "warning",
      "hier_label_mismatch": "error",
      "label_dangling": "error",
      "lib_symbol_issues": "warning",
      "missing_bidi_pin": "warning",
      "missing_input_pin": "warning",
      "missing_power_pin": "error",
      "missing_unit": "warning",
      "multiple_net_names": "warning",
      "net_not_bus_member": "warning",
      "no_connect_connected": "warning",
      "no_connect_dangling": "warning",
      "pin_not_connected": "error",
      "pin_not_driven": "error",
      "pin_to_pin": "error",
      "power_pin_not_driven": "error",
      "similar_labels": "warning",
      "simulation_model_issue": "ignore",
      "unannotated": "error",
      "unit_value_mismatch": "error",
      "unresolved_variable": "error",
      "wire_dangling": "error"
    }
  },
  "libraries": {
    "pinned_footprint_libs": [],
    "pinned_symbol_libs": []
  },
  "meta": {
    "filename": "jetson-orin-baseboard-oculink-expansion.kicad_pro",
    "version": 1
  },
  "net_settings": {
    "classes": [
      {
        "bus_width": 12,
        "clearance": 0.15,
        "diff_pair_gap": 0.25,
        "diff_pair_via_gap": 0.25,
        "diff_pair_width": 0.2,
        "line_style": 0,
        "microvia_diameter": 0.3,
        "microvia_drill": 0.1,
        "name": "Default",
        "pcb_color": "rgba(0, 0, 0, 0.000)",
        "schematic_color": "rgba(0, 0, 0, 0.000)",
        "track_width": 0.2,
        "via_diameter": 0.45,
        "via_drill": 0.1,
        "wire_width": 6
      },
      {
        "bus_width": 12,
        "clearance": 0.125,
        "diff_pair_gap": 0.2,
        "diff_pair_via_gap": 0.25,
        "diff_pair_width": 0.35,
        "line_style": 0,
        "microvia_diameter": 0.45,
        "microvia_drill": 0.1,
        "name": "85Ohm-diff_PCIE",
        "pcb_color": "rgba(0, 0, 0, 0.000)",
        "schematic_color": "rgba(0, 0, 0, 0.000)",
        "track_width": 0.15,
        "via_diameter": 0.45,
        "via_drill": 0.1,
        "wire_width": 6
      }
    ],
    "meta": {
      "version": 3
    },
    "net_colors": null,
    "netclass_assignments": null,
    "netclass_patterns": [
      {
        "netclass": "Default",
        "pattern": "/TX_*"
      },
      {
        "netclass": "Default",
        "pattern": "/RX_*"
      },
      {
        "netclass": "85Ohm-diff_PCIE",
        "pattern": "*TX*"
      },
      {
        "netclass": "85Ohm-diff_PCIE",
        "pattern": "*RX*"
      },
      {
        "netclass": "85Ohm-diff_PCIE",
        "pattern": "*CLK*"
      }
    ]
  },
  "pcbnew": {
    "last_paths": {
      "gencad": "",
      "idf": "",
      "netlist": "",
      "plot": "",
      "pos_files": "",
      "specctra_dsn": "",
      "step": "jetson-orin-baseboard-oculink-expansion.step",
      "svg": "",
      "vrml": "jetson-orin-baseboard-oculink-expansion.wrl"
    },
    "page_layout_descr_file": ""
  },
  "schematic": {
    "annotate_start_num": 0,
    "bom_export_filename": "",
    "bom_fmt_presets": [],
    "bom_fmt_settings": {
      "field_delimiter": ",",
      "keep_line_breaks": false,
      "keep_tabs": false,
      "name": "CSV",
      "ref_delimiter": ",",
      "ref_range_delimiter": "",
      "string_delimiter": "\""
    },
    "bom_presets": [],
    "bom_settings": {
      "exclude_dnp": false,
      "fields_ordered": [
        {
          "group_by": false,
          "label": "Reference",
          "name": "Reference",
          "show": true
        },
        {
          "group_by": true,
          "label": "Value",
          "name": "Value",
          "show": true
        },
        {
          "group_by": false,
          "label": "Datasheet",
          "name": "Datasheet",
          "show": true
        },
        {
          "group_by": false,
          "label": "Footprint",
          "name": "Footprint",
          "show": true
        },
        {
          "group_by": false,
          "label": "Qty",
          "name": "${QUANTITY}",
          "show": true
        },
        {
          "group_by": true,
          "label": "DNP",
          "name": "${DNP}",
          "show": true
        }
      ],
      "filter_string": "",
      "group_symbols": true,
      "name": "Grouped By Value",
      "sort_asc": true,
      "sort_field": "Reference"
    },
    "connection_grid_size": 50.0,
    "drawing": {
      "dashed_lines_dash_length_ratio": 12.0,
      "dashed_lines_gap_length_ratio": 3.0,
      "default_line_thickness": 6.0,
      "default_text_size": 50.0,
      "field_names": [],
      "intersheets_ref_own_page": false,
      "intersheets_ref_prefix": "",
      "intersheets_ref_short": false,
      "intersheets_ref_show": false,
      "intersheets_ref_suffix": "",
      "junction_size_choice": 3,
      "label_size_ratio": 0.375,
      "operating_point_overlay_i_precision": 3,
      "operating_point_overlay_i_range": "~A",
      "operating_point_overlay_v_precision": 3,
      "operating_point_overlay_v_range": "~V",
      "overbar_offset_ratio": 1.23,
      "pin_symbol_size": 25.0,
      "text_offset_ratio": 0.15
    },
    "legacy_lib_dir": "",
    "legacy_lib_list": [],
    "meta": {
      "version": 1
    },
    "net_format_name": "",
    "page_layout_descr_file": "",
    "plot_directory": "",
    "spice_current_sheet_as_root": false,
    "spice_external_command": "spice \"%I\"",
    "spice_model_current_sheet_as_root": true,
    "spice_save_all_currents": false,
    "spice_save_all_dissipations": false,
    "spice_save_all_voltages": false,
    "subpart_first_id": 65,
    "subpart_id_separator": 0
  },
  "sheets": [
    [
      "",
      "Root"
    ]
  ],
  "text_variables": {}
}
